(kicad_pcb
	(version 20260206)
	(generator "pcbnew")
	(generator_version "10.0")
	(general
		(thickness 1.6)
		(legacy_teardrops no)
	)
	(paper "A4")
	(title_block
		(title "01162023_DA0F0TEBIF0_F0T_Expander_BD_F_brd_V02_OCP.brd")
		(comment 1 "Grand Teton / footprints 4306-4308 of 9728")
	)
	(layers
		(0 "F.Cu" signal "TOP")
		(4 "In1.Cu" signal "GND")
		(6 "In2.Cu" signal "VCC")
		(8 "In3.Cu" signal "VCC1")
		(10 "In4.Cu" signal "GND1")
		(12 "In5.Cu" signal "IN1")
		(14 "In6.Cu" signal "GND2")
		(16 "In7.Cu" signal "IN2")
		(18 "In8.Cu" signal "GND3")
		(20 "In9.Cu" signal "IN3")
		(22 "In10.Cu" signal "GND4")
		(24 "In11.Cu" signal "IN4")
		(26 "In12.Cu" signal "GND5")
		(28 "In13.Cu" signal "IN5")
		(30 "In14.Cu" signal "GND6")
		(32 "In15.Cu" signal "IN6")
		(34 "In16.Cu" signal "GND7")
		(2 "B.Cu" signal "BOTTOM")
		(9 "F.Adhes" user "F.Adhesive")
		(11 "B.Adhes" user "B.Adhesive")
		(13 "F.Paste" user "Package Geometry/Pastemask Top")
		(15 "B.Paste" user "Package Geometry/Pastemask Bottom")
		(5 "F.SilkS" user "Ref Des/Silkscreen Top")
		(7 "B.SilkS" user "Ref Des/Silkscreen Bottom")
		(1 "F.Mask" user "Board Geometry/Soldermask Top")
		(3 "B.Mask" user "Board Geometry/Soldermask Bottom")
		(17 "Dwgs.User" user "User.Drawings")
		(19 "Cmts.User" user "User.Comments")
		(21 "Eco1.User" user "User.Eco1")
		(23 "Eco2.User" user "User.Eco2")
		(25 "Edge.Cuts" user "Board Geometry/Outline")
		(27 "Margin" user)
		(31 "F.CrtYd" user "Package Geometry/Place Bound Top")
		(29 "B.CrtYd" user "Package Geometry/Place Bound Bottom")
		(35 "F.Fab" user "Ref Des/Assembly Top")
		(33 "B.Fab" user "Ref Des/Assembly Bottom")
	)
	(footprint ""
		(layer "F.Cu")
		(at 362.9914 -284.8991 180)
		(property "Reference" "PU15"
			(at -8.419592 -2.676398 90)
			(unlocked yes)
			(layer "F.SilkS")
			(effects
				(font
					(size 0.7874 0.5842)
					(thickness 0.1524)
				)
				(justify left)
			)
		)
		(property "Value" ""
			(at 0 0 180)
			(layer "F.Fab")
			(effects
				(font
					(size 1.27 1.27)
				)
			)
		)
		(duplicate_pad_numbers_are_jumpers no)
		(fp_line
			(start 2.500122 2.999994)
			(end 2.2987 2.999994)
			(stroke
				(width 0.1524)
				(type default)
			)
			(layer "F.SilkS")
		)
		(fp_line
			(start 2.500122 2.339594)
			(end 2.500122 2.999994)
			(stroke
				(width 0.1524)
				(type default)
			)
			(layer "F.SilkS")
		)
		(fp_line
			(start 2.500122 -2.999994)
			(end 2.500122 -2.44348)
			(stroke
				(width 0.1524)
				(type default)
			)
			(layer "F.SilkS")
		)
		(fp_line
			(start 2.31394 -2.999994)
			(end 2.500122 -2.999994)
			(stroke
				(width 0.1524)
				(type default)
			)
			(layer "F.SilkS")
		)
		(fp_line
			(start -2.2987 2.999994)
			(end -2.500122 2.999994)
			(stroke
				(width 0.1524)
				(type default)
			)
			(layer "F.SilkS")
		)
		(fp_line
			(start -2.500122 2.999994)
			(end -2.500122 2.339594)
			(stroke
				(width 0.1524)
				(type default)
			)
			(layer "F.SilkS")
		)
		(fp_line
			(start -2.500122 0.6604)
			(end -2.500122 0.229108)
			(stroke
				(width 0.1524)
				(type default)
			)
			(layer "F.SilkS")
		)
		(fp_line
			(start -2.500122 -2.529078)
			(end -2.500122 -2.999994)
			(stroke
				(width 0.1524)
				(type default)
			)
			(layer "F.SilkS")
		)
		(fp_line
			(start -2.500122 -2.999994)
			(end -2.24409 -2.999994)
			(stroke
				(width 0.1524)
				(type default)
			)
			(layer "F.SilkS")
		)
		(fp_poly
			(pts
				(xy -4.495292 -3.711702) (xy -5.213858 -2.99339) (xy -4.136136 -2.634234)
			)
			(stroke
				(width 0)
				(type default)
			)
			(fill yes)
			(layer "F.SilkS")
		)
		(fp_line
			(start 2.500122 2.999994)
			(end -2.500122 2.999994)
			(stroke
				(width 0.1)
				(type default)
			)
			(layer "F.Fab")
		)
		(fp_line
			(start 2.500122 -2.999994)
			(end 2.500122 2.999994)
			(stroke
				(width 0.1)
				(type default)
			)
			(layer "F.Fab")
		)
		(fp_line
			(start -2.500122 2.999994)
			(end -2.500122 -2.999994)
			(stroke
				(width 0.1)
				(type default)
			)
			(layer "F.Fab")
		)
		(fp_line
			(start -2.500122 -2.999994)
			(end 2.500122 -2.999994)
			(stroke
				(width 0.1)
				(type default)
			)
			(layer "F.Fab")
		)
		(fp_poly
			(pts
				(xy -4.218432 -2.783078) (xy -4.218432 -1.767078) (xy -3.202432 -2.275078)
			)
			(stroke
				(width 0)
				(type default)
			)
			(fill yes)
			(layer "F.Fab")
		)
		(pad "1" smd rect
			(at -2.400046 -2.275078 270)
			(size 0.2286 0.6096)
			(layers "F.Cu" "F.Mask" "F.Paste")
			(net "SW_P0V8_PEX3_VOS2")
		)
		(pad "2" smd rect
			(at -2.400046 -1.82499 270)
			(size 0.2286 0.6096)
			(layers "F.Cu" "F.Mask" "F.Paste")
			(net "GND")
		)
		(pad "3" smd rect
			(at -2.400046 -1.374902 270)
			(size 0.2286 0.6096)
			(layers "F.Cu" "F.Mask" "F.Paste")
			(net "P0V8_PEX3_VCC2")
		)
		(pad "4" smd rect
			(at -2.400046 -0.925068 270)
			(size 0.2286 0.6096)
			(layers "F.Cu" "F.Mask" "F.Paste")
			(net "P0V8_PEX3_PVCC")
		)
		(pad "5" smd rect
			(at -2.400046 -0.47498 270)
			(size 0.2286 0.6096)
			(layers "F.Cu" "F.Mask" "F.Paste")
			(net "GND")
		)
		(pad "6" smd rect
			(at -2.400046 -0.024892 270)
			(size 0.2286 0.6096)
			(layers "F.Cu" "F.Mask" "F.Paste")
			(net "NC_P0V8_PEX3_PH2_NC1")
		)
		(pad "7_9-20_24" smd circle
			(at 0 1.150112 270)
			(size 0 0)
			(layers "F.Cu" "F.Mask" "F.Paste")
			(net "GND")
		)
		(pad "10_19" smd rect
			(at 0 2.899918 270)
			(size 0.6096 4.318)
			(layers "F.Cu" "F.Mask" "F.Paste")
			(net "SW_P0V8_PEX3_PH2")
		)
		(pad "25_29" smd rect
			(at 1.549908 -1.279906 90)
			(size 2.0574 2.3114)
			(layers "F.Cu" "F.Mask" "F.Paste")
			(net "SW_P12V_P0V8_PEX3_FLT")
		)
		(pad "30" smd rect
			(at 2.05994 -2.899918 180)
			(size 0.2286 0.6096)
			(layers "F.Cu" "F.Mask" "F.Paste")
			(net "SW_P12V_P0V8_PEX3_FLT")
		)
		(pad "31" smd rect
			(at 1.610106 -2.899918 180)
			(size 0.2286 0.6096)
			(layers "F.Cu" "F.Mask" "F.Paste")
			(net "NC_P0V8_PEX3_PH2_NC3")
		)
		(pad "32" smd rect
			(at 1.160018 -2.899918 180)
			(size 0.2286 0.6096)
			(layers "F.Cu" "F.Mask" "F.Paste")
			(net "SW_P0V8_PEX3_PHASE2")
		)
		(pad "33" smd rect
			(at 0.70993 -2.899918 180)
			(size 0.2286 0.6096)
			(layers "F.Cu" "F.Mask" "F.Paste")
			(net "SW_P0V8_PEX3_BOOT2")
		)
		(pad "34" smd rect
			(at 0.260096 -2.899918 180)
			(size 0.2286 0.6096)
			(layers "F.Cu" "F.Mask" "F.Paste")
			(net "P0V8_PEX3_PWM2")
		)
		(pad "35" smd rect
			(at -0.189992 -2.899918 180)
			(size 0.2286 0.6096)
			(layers "F.Cu" "F.Mask" "F.Paste")
			(net "P0V8_PEX2_EN4")
		)
		(pad "36" smd rect
			(at -0.64008 -2.899918 180)
			(size 0.2286 0.6096)
			(layers "F.Cu" "F.Mask" "F.Paste")
			(net "P0V8_PEX3_TSEN")
		)
		(pad "37" smd rect
			(at -1.089914 -2.899918 180)
			(size 0.2286 0.6096)
			(layers "F.Cu" "F.Mask" "F.Paste")
			(net "P0V8_PEX3_LSET2")
		)
		(pad "38" smd rect
			(at -1.540002 -2.899918 180)
			(size 0.2286 0.6096)
			(layers "F.Cu" "F.Mask" "F.Paste")
			(net "P0V8_PEX3_ISEN2")
		)
		(pad "39" smd rect
			(at -1.99009 -2.899918 180)
			(size 0.2286 0.6096)
			(layers "F.Cu" "F.Mask" "F.Paste")
			(net "P0V8_PEX2_VREF")
		)
		(pad "40" smd rect
			(at -0.87503 -1.27508 180)
			(size 1.7526 1.9558)
			(layers "F.Cu" "F.Mask" "F.Paste")
			(net "GND")
		)
		(pad "41" smd rect
			(at -1.525016 0.249936 90)
			(size 0.3048 0.4572)
			(layers "F.Cu" "F.Mask" "F.Paste")
			(net "NC_P0V8_PEX3_PH2_NC2")
		)
		(zone
			(layer "F.Cu")
			(hatch none 0.5)
			(connect_pads
				(clearance 0)
			)
			(min_thickness 0.25)
			(keepout
				(tracks not_allowed)
				(vias allowed)
				(pads allowed)
				(copperpour not_allowed)
				(footprints allowed)
			)
			(placement
				(enabled no)
				(sheetname "")
			)
			(fill
				(thermal_gap 0.5)
				(thermal_bridge_width 0.5)
				(island_removal_mode 0)
			)
			(polygon
				(pts
					(xy 365.491522 -287.899094) (xy 365.491522 -287.149794) (xy 360.491278 -287.149794) (xy 360.491278 -287.899094)
					(xy 360.7816 -287.899094) (xy 360.7816 -287.443418) (xy 365.2012 -287.443418) (xy 365.2012 -287.899094)
				)
			)
		)
	)
	(footprint ""
		(layer "F.Cu")
		(at 233.425746 -115.936268 180)
		(property "Reference" "PU74"
			(at 3.656076 -1.433068 90)
			(unlocked yes)
			(layer "F.SilkS")
			(effects
				(font
					(size 0.7874 0.5842)
					(thickness 0.1524)
				)
				(justify left)
			)
		)
		(property "Value" ""
			(at 0 0 180)
			(layer "F.Fab")
			(effects
				(font
					(size 1.27 1.27)
				)
			)
		)
		(duplicate_pad_numbers_are_jumpers no)
		(fp_line
			(start 1.549908 2.549906)
			(end 1.549908 2.253996)
			(stroke
				(width 0.1524)
				(type default)
			)
			(layer "F.SilkS")
		)
		(fp_line
			(start 1.549908 -2.253996)
			(end 1.549908 -2.549906)
			(stroke
				(width 0.1524)
				(type default)
			)
			(layer "F.SilkS")
		)
		(fp_line
			(start 1.549908 -2.549906)
			(end 0.752094 -2.549906)
			(stroke
				(width 0.1524)
				(type default)
			)
			(layer "F.SilkS")
		)
		(fp_line
			(start 0.753872 2.549906)
			(end 1.549908 2.549906)
			(stroke
				(width 0.1524)
				(type default)
			)
			(layer "F.SilkS")
		)
		(fp_line
			(start 0.2413 -2.549906)
			(end -0.2413 -2.549906)
			(stroke
				(width 0.1524)
				(type default)
			)
			(layer "F.SilkS")
		)
		(fp_line
			(start -0.245872 2.549906)
			(end 0.245872 2.549906)
			(stroke
				(width 0.1524)
				(type default)
			)
			(layer "F.SilkS")
		)
		(fp_line
			(start -0.752094 -2.549906)
			(end -1.549908 -2.549906)
			(stroke
				(width 0.1524)
				(type default)
			)
			(layer "F.SilkS")
		)
		(fp_line
			(start -1.549908 2.549906)
			(end -0.753872 2.549906)
			(stroke
				(width 0.1524)
				(type default)
			)
			(layer "F.SilkS")
		)
		(fp_line
			(start -1.549908 2.253996)
			(end -1.549908 2.549906)
			(stroke
				(width 0.1524)
				(type default)
			)
			(layer "F.SilkS")
		)
		(fp_line
			(start -1.549908 -2.549906)
			(end -1.549908 -2.251964)
			(stroke
				(width 0.1524)
				(type default)
			)
			(layer "F.SilkS")
		)
		(fp_poly
			(pts
				(xy -1.891538 -1.999996) (xy -2.7432 -1.574292) (xy -2.7432 -2.4257)
			)
			(stroke
				(width 0)
				(type default)
			)
			(fill yes)
			(layer "F.SilkS")
		)
		(fp_line
			(start 1.549908 2.549906)
			(end 1.549908 -2.549906)
			(stroke
				(width 0.1)
				(type default)
			)
			(layer "F.Fab")
		)
		(fp_line
			(start 1.549908 -2.549906)
			(end -1.549908 -2.549906)
			(stroke
				(width 0.1)
				(type default)
			)
			(layer "F.Fab")
		)
		(fp_line
			(start -1.549908 2.549906)
			(end 1.549908 2.549906)
			(stroke
				(width 0.1)
				(type default)
			)
			(layer "F.Fab")
		)
		(fp_line
			(start -1.549908 -2.549906)
			(end -1.549908 2.549906)
			(stroke
				(width 0.1)
				(type default)
			)
			(layer "F.Fab")
		)
		(fp_poly
			(pts
				(xy -1.891538 -1.999996) (xy -2.7432 -1.574292) (xy -2.7432 -2.4257)
			)
			(stroke
				(width 0)
				(type default)
			)
			(fill yes)
			(layer "F.Fab")
		)
		(fp_text user "12"
			(at 2.71272 1.070864 90)
			(unlocked yes)
			(layer "F.SilkS")
			(effects
				(font
					(size 0.635 0.4064)
					(thickness 0.1524)
				)
			)
		)
		(fp_text user "20"
			(at 2.055368 -2.7686 90)
			(unlocked yes)
			(layer "F.SilkS")
			(effects
				(font
					(size 0.635 0.4064)
					(thickness 0.1524)
				)
			)
		)
		(fp_text user "11"
			(at 1.808734 3.022092 180)
			(unlocked yes)
			(layer "F.SilkS")
			(effects
				(font
					(size 0.635 0.4064)
					(thickness 0.1524)
				)
			)
		)
		(fp_text user "21_22"
			(at -0.745744 -3.513836 0)
			(unlocked yes)
			(layer "F.SilkS")
			(effects
				(font
					(size 0.635 0.4064)
					(thickness 0.1524)
				)
			)
		)
		(fp_text user "10"
			(at -1.4224 3.253232 180)
			(unlocked yes)
			(layer "F.SilkS")
			(effects
				(font
					(size 0.635 0.4064)
					(thickness 0.1524)
				)
			)
		)
		(fp_text user "9"
			(at -2.338832 2.5908 90)
			(unlocked yes)
			(layer "F.SilkS")
			(effects
				(font
					(size 0.635 0.4064)
					(thickness 0.1524)
				)
			)
		)
		(fp_text user "12"
			(at 2.207768 2.7178 90)
			(unlocked yes)
			(layer "F.Fab")
			(effects
				(font
					(size 0.635 0.4064)
					(thickness 0.1524)
				)
			)
		)
		(fp_text user "20"
			(at 2.055368 -2.7686 90)
			(unlocked yes)
			(layer "F.Fab")
			(effects
				(font
					(size 0.635 0.4064)
					(thickness 0.1524)
				)
			)
		)
		(fp_text user "11"
			(at 1.1938 3.329432 180)
			(unlocked yes)
			(layer "F.Fab")
			(effects
				(font
					(size 0.635 0.4064)
					(thickness 0.1524)
				)
			)
		)
		(fp_text user "21_22"
			(at -0.0762 -3.401568 180)
			(unlocked yes)
			(layer "F.Fab")
			(effects
				(font
					(size 0.635 0.4064)
					(thickness 0.1524)
				)
			)
		)
		(fp_text user "10"
			(at -1.4224 3.253232 180)
			(unlocked yes)
			(layer "F.Fab")
			(effects
				(font
					(size 0.635 0.4064)
					(thickness 0.1524)
				)
			)
		)
		(fp_text user "9"
			(at -2.338832 2.5908 90)
			(unlocked yes)
			(layer "F.Fab")
			(effects
				(font
					(size 0.635 0.4064)
					(thickness 0.1524)
				)
			)
		)
		(pad "1" smd circle
			(at -1.374902 -1.999996 90)
			(size 0 0)
			(layers "F.Cu" "F.Mask" "F.Paste")
			(net "P12V_NIC3_CO_EN")
		)
		(pad "2" smd rect
			(at -1.400048 -1.500124 90)
			(size 0.254 0.8128)
			(layers "F.Cu" "F.Mask" "F.Paste")
			(net "GND")
		)
		(pad "3" smd rect
			(at -1.400048 -0.999998 90)
			(size 0.254 0.8128)
			(layers "F.Cu" "F.Mask" "F.Paste")
			(net "GND")
		)
		(pad "4" smd rect
			(at -1.400048 -0.499872 90)
			(size 0.254 0.8128)
			(layers "F.Cu" "F.Mask" "F.Paste")
			(net "P12V_NIC3_CO_TIMER")
		)
		(pad "5" smd rect
			(at -1.400048 0 90)
			(size 0.254 0.8128)
			(layers "F.Cu" "F.Mask" "F.Paste")
			(net "P12V_NIC3_CO_ISET")
		)
		(pad "6" smd rect
			(at -1.400048 0.499872 90)
			(size 0.254 0.8128)
			(layers "F.Cu" "F.Mask" "F.Paste")
			(net "P12V_NIC3_CO_SS")
		)
		(pad "7" smd rect
			(at -1.400048 0.999998 90)
			(size 0.254 0.8128)
			(layers "F.Cu" "F.Mask" "F.Paste")
			(net "GND")
		)
		(pad "8" smd rect
			(at -1.400048 1.500124 90)
			(size 0.254 0.8128)
			(layers "F.Cu" "F.Mask" "F.Paste")
			(net "P12V_NIC3_CO_IMON_VR")
		)
		(pad "9" smd rect
			(at -1.400048 1.999996 90)
			(size 0.254 0.8128)
			(layers "F.Cu" "F.Mask" "F.Paste")
			(net "P12V_NIC3_CO_FLTB")
		)
		(pad "10" smd rect
			(at -0.499872 2.400046 180)
			(size 0.254 0.8128)
			(layers "F.Cu" "F.Mask" "F.Paste")
			(net "PWRGD_P12V_NIC3_CO")
		)
		(pad "11" smd rect
			(at 0.499872 2.400046 180)
			(size 0.254 0.8128)
			(layers "F.Cu" "F.Mask" "F.Paste")
			(net "P12V_NIC3_CO_OV_FB")
		)
		(pad "12" smd rect
			(at 1.400048 1.999996 90)
			(size 0.254 0.8128)
			(layers "F.Cu" "F.Mask" "F.Paste")
			(net "P12V_NIC3_CO_AVIN_PD")
		)
		(pad "13" smd rect
			(at 1.400048 1.500124 90)
			(size 0.254 0.8128)
			(layers "F.Cu" "F.Mask" "F.Paste")
			(net "P12V_NIC3_R")
		)
		(pad "14" smd rect
			(at 1.400048 0.999998 90)
			(size 0.254 0.8128)
			(layers "F.Cu" "F.Mask" "F.Paste")
			(net "P12V_NIC3_R")
		)
		(pad "15" smd rect
			(at 1.400048 0.499872 90)
			(size 0.254 0.8128)
			(layers "F.Cu" "F.Mask" "F.Paste")
			(net "P12V_NIC3_R")
		)
		(pad "16" smd rect
			(at 1.400048 0 90)
			(size 0.254 0.8128)
			(layers "F.Cu" "F.Mask" "F.Paste")
			(net "P12V_NIC3_R")
		)
		(pad "17" smd rect
			(at 1.400048 -0.499872 90)
			(size 0.254 0.8128)
			(layers "F.Cu" "F.Mask" "F.Paste")
			(net "P12V_NIC3_R")
		)
		(pad "18" smd rect
			(at 1.400048 -0.999998 90)
			(size 0.254 0.8128)
			(layers "F.Cu" "F.Mask" "F.Paste")
			(net "P12V_NIC3_R")
		)
		(pad "19" smd rect
			(at 1.400048 -1.500124 90)
			(size 0.254 0.8128)
			(layers "F.Cu" "F.Mask" "F.Paste")
			(net "P12V_NIC3_R")
		)
		(pad "20" smd rect
			(at 1.400048 -1.999996 90)
			(size 0.254 0.8128)
			(layers "F.Cu" "F.Mask" "F.Paste")
			(net "P12V_NIC3_R")
		)
		(pad "21_22" smd circle
			(at 0.499872 -2.337562 90)
			(size 0 0)
			(layers "F.Cu" "F.Mask" "F.Paste")
			(net "P12V_AUX")
		)
		(pad "23" smd rect
			(at 0 -1.100074 90)
			(size 0.254 1.27)
			(layers "F.Cu" "F.Mask" "F.Paste")
			(net "P12V_AUX")
		)
		(pad "24" smd rect
			(at 0 -0.199898 90)
			(size 0.254 1.27)
			(layers "F.Cu" "F.Mask" "F.Paste")
			(net "P12V_AUX")
		)
		(pad "25" smd rect
			(at 0 0.700024 90)
			(size 0.254 1.27)
			(layers "F.Cu" "F.Mask" "F.Paste")
			(net "P12V_AUX")
		)
		(pad "26" smd rect
			(at 0 1.599946 90)
			(size 0.254 1.27)
			(layers "F.Cu" "F.Mask" "F.Paste")
			(net "P12V_AUX")
		)
	)
	(footprint ""
		(layer "F.Cu")
		(at 409.269692 -350.098614 90)
		(property "Reference" "C2439"
			(at 0 0 90)
			(layer "F.SilkS")
			(hide yes)
			(effects
				(font
					(size 1.27 1.27)
				)
			)
		)
		(property "Value" ""
			(at 0 0 90)
			(layer "F.Fab")
			(effects
				(font
					(size 1.27 1.27)
				)
			)
		)
		(duplicate_pad_numbers_are_jumpers no)
		(fp_line
			(start 0.299974 -0.150114)
			(end 0.299974 0.150114)
			(stroke
				(width 0.1)
				(type default)
			)
			(layer "F.Fab")
		)
		(fp_line
			(start -0.299974 -0.150114)
			(end 0.299974 -0.150114)
			(stroke
				(width 0.1)
				(type default)
			)
			(layer "F.Fab")
		)
		(fp_line
			(start 0.299974 0.150114)
			(end -0.299974 0.150114)
			(stroke
				(width 0.1)
				(type default)
			)
			(layer "F.Fab")
		)
		(fp_line
			(start -0.299974 0.150114)
			(end -0.299974 -0.150114)
			(stroke
				(width 0.1)
				(type default)
			)
			(layer "F.Fab")
		)
		(pad "1" smd rect
			(at -0.2667 0 90)
			(size 0.3048 0.381)
			(layers "F.Cu" "F.Mask" "F.Paste")
			(net "P5E_PEX3_STN4_TX_DP<79>")
		)
		(pad "2" smd rect
			(at 0.2667 0 90)
			(size 0.3048 0.381)
			(layers "F.Cu" "F.Mask" "F.Paste")
			(net "P5E_PEX3_STN4_TX_C_DP<79>")
		)
	)
)
